(kicad_pcb
	(version 20240108)
	(generator "pcbnew")
	(generator_version "8.0")
	(general
		(thickness 1.586)
		(legacy_teardrops no)
	)
	(paper "A4")
	(title_block
		(title "GMSL Serializer")
		(date "2024-11-27")
		(rev "1.1.1")
		(company "Antmicro Ltd")
		(comment 1 "www.antmicro.com")
		(comment 9 "footprints 68-72 of 117")
	)
	(layers
		(0 "F.Cu" signal)
		(1 "In1.Cu" power)
		(2 "In2.Cu" power)
		(31 "B.Cu" signal)
		(32 "B.Adhes" user "B.Adhesive")
		(33 "F.Adhes" user "F.Adhesive")
		(34 "B.Paste" user)
		(35 "F.Paste" user)
		(36 "B.SilkS" user "B.Silkscreen")
		(37 "F.SilkS" user "F.Silkscreen")
		(38 "B.Mask" user)
		(39 "F.Mask" user)
		(40 "Dwgs.User" user "User.Drawings")
		(41 "Cmts.User" user "User.Comments")
		(42 "Eco1.User" user "User.Eco1")
		(43 "Eco2.User" user "User.Eco2")
		(44 "Edge.Cuts" user)
		(45 "Margin" user)
		(46 "B.CrtYd" user "B.Courtyard")
		(47 "F.CrtYd" user "F.Courtyard")
		(48 "B.Fab" user)
		(49 "F.Fab" user)
	)
	(footprint "antmicro-footprints:Conn_FAKRA_59S2AQ-40MT5-Z_1"
		(layer "F.Cu")
		(at 153 79.998)
		(descr "Connector FAKRA, 5 pins")
		(property "Reference" "J2"
			(at 4.75 -0.998 0)
			(layer "F.SilkS")
			(effects
				(font
					(size 0.7 0.7)
					(thickness 0.15)
				)
				(justify left bottom)
			)
		)
		(property "Value" "Conn_FAKRA_59S2AQ-40MT5-Z_1"
			(at 10.668 5.588 0)
			(layer "F.Fab")
			(effects
				(font
					(size 0.7 0.7)
					(thickness 0.15)
				)
				(justify left bottom)
			)
		)
		(property "Footprint" "antmicro-footprints:Conn_FAKRA_59S2AQ-40MT5-Z_1"
			(at 0 0 0)
			(layer "F.Fab")
			(hide yes)
			(effects
				(font
					(size 1.27 1.27)
					(thickness 0.15)
				)
			)
		)
		(property "Datasheet" "https://products.rosenberger.com/radio-frequency/connectors/288881/59s2aq-40mt5-z-1-right-angle-plug-pcb-w.-housing"
			(at 0 0 0)
			(layer "F.Fab")
			(hide yes)
			(effects
				(font
					(size 1.27 1.27)
					(thickness 0.15)
				)
			)
		)
		(property "Author" "Antmicro"
			(at 0 0 0)
			(layer "F.Fab")
			(hide yes)
			(effects
				(font
					(size 1 1)
					(thickness 0.15)
				)
			)
		)
		(property "License" "Apache-2.0"
			(at 0 0 0)
			(layer "F.Fab")
			(hide yes)
			(effects
				(font
					(size 1 1)
					(thickness 0.15)
				)
			)
		)
		(property "MPN" "59S2AQ-40MT5-Z_1"
			(at 0 0 0)
			(layer "F.Fab")
			(hide yes)
			(effects
				(font
					(size 1 1)
					(thickness 0.15)
				)
			)
		)
		(property "Manufacturer" "Rosenberger"
			(at 0 0 0)
			(layer "F.Fab")
			(hide yes)
			(effects
				(font
					(size 1 1)
					(thickness 0.15)
				)
			)
		)
		(property ki_fp_filters "*BNC* *SMA* *SMB* *SMC* *Cinch*")
		(sheetname "GMSL Connector")
		(sheetfile "GMSL.kicad_sch")
		(attr smd)
		(fp_line
			(start -4.572 -2.004)
			(end -4.572 11.204)
			(stroke
				(width 0.15)
				(type solid)
			)
			(layer "F.SilkS")
		)
		(fp_line
			(start -4.572 11.204)
			(end 4.572 11.204)
			(stroke
				(width 0.15)
				(type solid)
			)
			(layer "F.SilkS")
		)
		(fp_line
			(start 4.572 -2.004)
			(end -4.572 -2.004)
			(stroke
				(width 0.15)
				(type solid)
			)
			(layer "F.SilkS")
		)
		(fp_line
			(start 4.572 11.204)
			(end 4.572 -2.004)
			(stroke
				(width 0.15)
				(type solid)
			)
			(layer "F.SilkS")
		)
		(fp_rect
			(start -5 -14)
			(end 5 10.86)
			(stroke
				(width 0.05)
				(type solid)
			)
			(fill none)
			(layer "F.CrtYd")
		)
		(fp_text user "Author: Antmicro"
			(at -5.35 14.404 0)
			(layer "F.Fab")
			(hide yes)
			(effects
				(font
					(size 0.7 0.7)
					(thickness 0.15)
				)
				(justify left bottom)
			)
		)
		(fp_text user "License: Apache-2.0"
			(at -5.35 13.204 0)
			(layer "F.Fab")
			(hide yes)
			(effects
				(font
					(size 0.7 0.7)
					(thickness 0.15)
				)
				(justify left bottom)
			)
		)
		(fp_text user "${REFERENCE}"
			(at -5.35 15.604 0)
			(layer "F.Fab")
			(hide yes)
			(effects
				(font
					(size 0.7 0.7)
					(thickness 0.15)
				)
				(justify left bottom)
			)
		)
		(pad "1" smd roundrect
			(at 0 0 270)
			(size 3.4 1.9)
			(layers "F.Cu" "F.Paste" "F.Mask")
			(roundrect_rratio 0.25)
			(net 18 "/GMSL Connector/SIO_P")
			(pinfunction "1")
			(pintype "passive")
		)
		(pad "2" thru_hole circle
			(at -3 0.6 270)
			(size 1.8 1.8)
			(drill 1.45)
			(layers "*.Cu" "*.Mask")
			(remove_unused_layers no)
			(net 1 "GND")
			(pinfunction "2")
			(pintype "passive")
		)
		(pad "2" smd roundrect
			(at -3 0.9 270)
			(size 5.2 1.8)
			(layers "F.Cu" "F.Paste" "F.Mask")
			(roundrect_rratio 0.25)
			(net 1 "GND")
			(pinfunction "2")
			(pintype "passive")
		)
		(pad "3" thru_hole circle
			(at -3 7.6 270)
			(size 1.8 1.8)
			(drill 1.45)
			(layers "*.Cu" "*.Mask")
			(remove_unused_layers no)
			(net 1 "GND")
			(pinfunction "3")
			(pintype "passive")
		)
		(pad "3" smd roundrect
			(at -3 8.1 270)
			(size 5.6 1.8)
			(layers "F.Cu" "F.Paste" "F.Mask")
			(roundrect_rratio 0.25)
			(net 1 "GND")
			(pinfunction "3")
			(pintype "passive")
		)
		(pad "4" thru_hole circle
			(at 3 7.6 270)
			(size 1.8 1.8)
			(drill 1.45)
			(layers "*.Cu" "*.Mask")
			(remove_unused_layers no)
			(net 1 "GND")
			(pinfunction "4")
			(pintype "passive")
		)
		(pad "4" smd roundrect
			(at 3 8.1 270)
			(size 5.6 1.8)
			(layers "F.Cu" "F.Paste" "F.Mask")
			(roundrect_rratio 0.25)
			(net 1 "GND")
			(pinfunction "4")
			(pintype "passive")
		)
		(pad "5" thru_hole circle
			(at 3 0.6 270)
			(size 1.8 1.8)
			(drill 1.45)
			(layers "*.Cu" "*.Mask")
			(remove_unused_layers no)
			(net 1 "GND")
			(pinfunction "5")
			(pintype "passive")
		)
		(pad "5" smd roundrect
			(at 3 0.9 270)
			(size 5.2 1.8)
			(layers "F.Cu" "F.Paste" "F.Mask")
			(roundrect_rratio 0.25)
			(net 1 "GND")
			(pinfunction "5")
			(pintype "passive")
		)
	)
	(footprint "antmicro-footprints:R_0402_1005Metric"
		(layer "F.Cu")
		(at 133.1 108.75)
		(descr "Resistor SMD 0402")
		(tags "resistor SMD 0402")
		(property "Reference" "R4"
			(at 1.05 -5.241666 0)
			(layer "F.SilkS")
			(effects
				(font
					(size 0.7 0.7)
					(thickness 0.15)
				)
				(justify left bottom)
			)
		)
		(property "Value" "R_100R_0402"
			(at -1.011843 1.772047 0)
			(layer "F.Fab")
			(effects
				(font
					(size 0.7 0.7)
					(thickness 0.15)
				)
				(justify left bottom)
			)
		)
		(property "Footprint" "antmicro-footprints:R_0402_1005Metric"
			(at 0 0 0)
			(layer "F.Fab")
			(hide yes)
			(effects
				(font
					(size 1.27 1.27)
					(thickness 0.15)
				)
			)
		)
		(property "Datasheet" "https://www.bourns.com/docs/product-datasheets/cr.pdf"
			(at 0 0 0)
			(layer "F.Fab")
			(hide yes)
			(effects
				(font
					(size 1.27 1.27)
					(thickness 0.15)
				)
			)
		)
		(property "Author" "Antmicro"
			(at 0 0 0)
			(layer "F.Fab")
			(hide yes)
			(effects
				(font
					(size 1 1)
					(thickness 0.15)
				)
			)
		)
		(property "License" "Apache-2.0"
			(at 0 0 0)
			(layer "F.Fab")
			(hide yes)
			(effects
				(font
					(size 1 1)
					(thickness 0.15)
				)
			)
		)
		(property "MPN" "CR0402-FX-1000GLF"
			(at 0 0 0)
			(layer "F.Fab")
			(hide yes)
			(effects
				(font
					(size 1 1)
					(thickness 0.15)
				)
			)
		)
		(property "Manufacturer" "Bourns"
			(at 0 0 0)
			(layer "F.Fab")
			(hide yes)
			(effects
				(font
					(size 1 1)
					(thickness 0.15)
				)
			)
		)
		(property "Tolerance" "1%"
			(at 0 0 0)
			(layer "F.Fab")
			(hide yes)
			(effects
				(font
					(size 1 1)
					(thickness 0.15)
				)
			)
		)
		(property "Val" "100R"
			(at 0 0 0)
			(layer "F.Fab")
			(hide yes)
			(effects
				(font
					(size 1 1)
					(thickness 0.15)
				)
			)
		)
		(sheetname "CSI Connector")
		(sheetfile "CSI.kicad_sch")
		(attr smd)
		(fp_rect
			(start -0.925 -0.47)
			(end 0.925 0.47)
			(stroke
				(width 0.05)
				(type default)
			)
			(fill none)
			(layer "F.CrtYd")
		)
		(fp_rect
			(start -0.5 -0.25)
			(end 0.5 0.25)
			(stroke
				(width 0.15)
				(type solid)
			)
			(fill none)
			(layer "F.Fab")
		)
		(fp_text user "${REFERENCE}"
			(at -0.95 3.168 0)
			(layer "F.Fab")
			(hide yes)
			(effects
				(font
					(size 0.7 0.7)
					(thickness 0.15)
				)
				(justify left bottom)
			)
		)
		(fp_text user "License: Apache-2.0"
			(at -0.95 5.169 0)
			(layer "F.Fab")
			(hide yes)
			(effects
				(font
					(size 0.7 0.7)
					(thickness 0.15)
				)
				(justify left bottom)
			)
		)
		(fp_text user "Author: Antmicro"
			(at -0.95 4.169 0)
			(layer "F.Fab")
			(hide yes)
			(effects
				(font
					(size 0.7 0.7)
					(thickness 0.15)
				)
				(justify left bottom)
			)
		)
		(pad "1" smd roundrect
			(at -0.48 0)
			(size 0.59 0.64)
			(layers "F.Cu" "F.Paste" "F.Mask")
			(roundrect_rratio 0.25)
			(net 35 "/CSI Connector/SCL_CAM0")
			(pintype "passive")
		)
		(pad "2" smd roundrect
			(at 0.48 0)
			(size 0.59 0.64)
			(layers "F.Cu" "F.Paste" "F.Mask")
			(roundrect_rratio 0.25)
			(net 89 "/CSI Connector/I2C.SCL")
			(pintype "passive")
		)
	)
	(footprint "antmicro-footprints:C_0402_1005Metric"
		(layer "F.Cu")
		(at 156.23 99.79 135)
		(descr "Capacitor SMD 0402")
		(tags "capacitor SMD 0402")
		(property "Reference" "C17"
			(at -1.086116 0.681651 -45)
			(unlocked yes)
			(layer "F.SilkS")
			(effects
				(font
					(size 0.7 0.7)
					(thickness 0.15)
				)
				(justify right bottom)
			)
		)
		(property "Value" "C_33p_0402"
			(at -1.022927 2.155213 135)
			(layer "F.Fab")
			(effects
				(font
					(size 0.7 0.7)
					(thickness 0.15)
				)
				(justify left bottom)
			)
		)
		(property "Footprint" "antmicro-footprints:C_0402_1005Metric"
			(at 0 0 135)
			(layer "F.Fab")
			(hide yes)
			(effects
				(font
					(size 1.27 1.27)
					(thickness 0.15)
				)
			)
		)
		(property "Datasheet" "https://spicat.kyocera-avx.com/product/mlcc/chartview/04025A330FAT2A/"
			(at 0 0 135)
			(layer "F.Fab")
			(hide yes)
			(effects
				(font
					(size 1.27 1.27)
					(thickness 0.15)
				)
			)
		)
		(property "Author" "Antmicro"
			(at 337.263478 59.880893 0)
			(layer "F.Fab")
			(hide yes)
			(effects
				(font
					(size 1 1)
					(thickness 0.15)
				)
			)
		)
		(property "Dielectric" ""
			(at 337.263478 59.880893 0)
			(layer "F.Fab")
			(hide yes)
			(effects
				(font
					(size 1 1)
					(thickness 0.15)
				)
			)
		)
		(property "License" "Apache-2.0"
			(at 337.263478 59.880893 0)
			(layer "F.Fab")
			(hide yes)
			(effects
				(font
					(size 1 1)
					(thickness 0.15)
				)
			)
		)
		(property "MPN" "04025A330FAT2A"
			(at 337.263478 59.880893 0)
			(layer "F.Fab")
			(hide yes)
			(effects
				(font
					(size 1 1)
					(thickness 0.15)
				)
			)
		)
		(property "Manufacturer" "KYOCERA AVX"
			(at 337.263478 59.880893 0)
			(layer "F.Fab")
			(hide yes)
			(effects
				(font
					(size 1 1)
					(thickness 0.15)
				)
			)
		)
		(property "Val" "33p"
			(at 337.263478 59.880893 0)
			(layer "F.Fab")
			(hide yes)
			(effects
				(font
					(size 1 1)
					(thickness 0.15)
				)
			)
		)
		(property "Voltage" ""
			(at 337.263478 59.880893 0)
			(layer "F.Fab")
			(hide yes)
			(effects
				(font
					(size 1 1)
					(thickness 0.15)
				)
			)
		)
		(sheetname "Serializer")
		(sheetfile "serializer.kicad_sch")
		(attr smd)
		(fp_poly
			(pts
				(xy -0.925 -0.47) (xy 0.925 -0.47) (xy 0.925 0.47) (xy -0.925 0.47)
			)
			(stroke
				(width 0.05)
				(type default)
			)
			(fill none)
			(layer "F.CrtYd")
		)
		(fp_line
			(start 0.504 -0.25)
			(end 0.504 0.248)
			(stroke
				(width 0.15)
				(type solid)
			)
			(layer "F.Fab")
		)
		(fp_line
			(start 0.504 0.248)
			(end -0.494 0.248)
			(stroke
				(width 0.15)
				(type solid)
			)
			(layer "F.Fab")
		)
		(fp_line
			(start -0.494 -0.25)
			(end 0.504 -0.25)
			(stroke
				(width 0.15)
				(type solid)
			)
			(layer "F.Fab")
		)
		(fp_line
			(start -0.494 0.248)
			(end -0.494 -0.25)
			(stroke
				(width 0.15)
				(type solid)
			)
			(layer "F.Fab")
		)
		(fp_text user "Author: Antmicro"
			(at -0.939 3.399 135)
			(layer "F.Fab")
			(hide yes)
			(effects
				(font
					(size 0.7 0.7)
					(thickness 0.15)
				)
				(justify left bottom)
			)
		)
		(fp_text user "License: Apache-2.0"
			(at -0.939 5.799 135)
			(layer "F.Fab")
			(hide yes)
			(effects
				(font
					(size 0.7 0.7)
					(thickness 0.15)
				)
				(justify left bottom)
			)
		)
		(fp_text user "${REFERENCE}"
			(at -0.939 4.599 135)
			(layer "F.Fab")
			(hide yes)
			(effects
				(font
					(size 0.7 0.7)
					(thickness 0.15)
				)
				(justify left bottom)
			)
		)
		(pad "1" smd roundrect
			(at -0.48 0 135)
			(size 0.59 0.64)
			(layers "F.Cu" "F.Paste" "F.Mask")
			(roundrect_rratio 0.25)
			(net 1 "GND")
			(pintype "passive")
		)
		(pad "2" smd roundrect
			(at 0.48 0 135)
			(size 0.59 0.64)
			(layers "F.Cu" "F.Paste" "F.Mask")
			(roundrect_rratio 0.25)
			(net 14 "/Serializer/X2_R")
			(pintype "passive")
		)
	)
	(footprint "antmicro-footprints:R_0402_1005Metric"
		(layer "F.Cu")
		(at 148.15 111.355 180)
		(descr "Resistor SMD 0402")
		(tags "resistor SMD 0402")
		(property "Reference" "R21"
			(at 0.81 -0.41 0)
			(layer "F.SilkS")
			(effects
				(font
					(size 0.7 0.7)
					(thickness 0.15)
				)
				(justify right bottom)
			)
		)
		(property "Value" "R_10k_0402"
			(at -1.011843 1.772047 0)
			(layer "F.Fab")
			(effects
				(font
					(size 0.7 0.7)
					(thickness 0.15)
				)
				(justify right bottom)
			)
		)
		(property "Footprint" "antmicro-footprints:R_0402_1005Metric"
			(at 0 0 180)
			(layer "F.Fab")
			(hide yes)
			(effects
				(font
					(size 1.27 1.27)
					(thickness 0.15)
				)
			)
		)
		(property "Datasheet" "https://www.bourns.com/docs/product-datasheets/cr.pdf"
			(at 0 0 180)
			(layer "F.Fab")
			(hide yes)
			(effects
				(font
					(size 1.27 1.27)
					(thickness 0.15)
				)
			)
		)
		(property "Author" "Antmicro"
			(at 296.3 222.71 0)
			(layer "F.Fab")
			(hide yes)
			(effects
				(font
					(size 1 1)
					(thickness 0.15)
				)
			)
		)
		(property "License" "Apache-2.0"
			(at 296.3 222.71 0)
			(layer "F.Fab")
			(hide yes)
			(effects
				(font
					(size 1 1)
					(thickness 0.15)
				)
			)
		)
		(property "MPN" "CR0402-FX-1002GLF"
			(at 296.3 222.71 0)
			(layer "F.Fab")
			(hide yes)
			(effects
				(font
					(size 1 1)
					(thickness 0.15)
				)
			)
		)
		(property "Manufacturer" "Bourns"
			(at 296.3 222.71 0)
			(layer "F.Fab")
			(hide yes)
			(effects
				(font
					(size 1 1)
					(thickness 0.15)
				)
			)
		)
		(property "Tolerance" "1%"
			(at 296.3 222.71 0)
			(layer "F.Fab")
			(hide yes)
			(effects
				(font
					(size 1 1)
					(thickness 0.15)
				)
			)
		)
		(property "Val" "10k"
			(at 296.3 222.71 0)
			(layer "F.Fab")
			(hide yes)
			(effects
				(font
					(size 1 1)
					(thickness 0.15)
				)
			)
		)
		(sheetname "Serializer")
		(sheetfile "serializer.kicad_sch")
		(attr smd)
		(fp_rect
			(start -0.925 -0.47)
			(end 0.925 0.47)
			(stroke
				(width 0.05)
				(type default)
			)
			(fill none)
			(layer "F.CrtYd")
		)
		(fp_rect
			(start -0.5 -0.25)
			(end 0.5 0.25)
			(stroke
				(width 0.15)
				(type solid)
			)
			(fill none)
			(layer "F.Fab")
		)
		(fp_text user "Author: Antmicro"
			(at -0.95 4.169 0)
			(layer "F.Fab")
			(hide yes)
			(effects
				(font
					(size 0.7 0.7)
					(thickness 0.15)
				)
				(justify right bottom)
			)
		)
		(fp_text user "${REFERENCE}"
			(at -0.95 3.168 0)
			(layer "F.Fab")
			(hide yes)
			(effects
				(font
					(size 0.7 0.7)
					(thickness 0.15)
				)
				(justify right bottom)
			)
		)
		(fp_text user "License: Apache-2.0"
			(at -0.95 5.169 0)
			(layer "F.Fab")
			(hide yes)
			(effects
				(font
					(size 0.7 0.7)
					(thickness 0.15)
				)
				(justify right bottom)
			)
		)
		(pad "1" smd roundrect
			(at -0.48 0 180)
			(size 0.59 0.64)
			(layers "F.Cu" "F.Paste" "F.Mask")
			(roundrect_rratio 0.25)
			(net 68 "/Serializer/CFG1")
			(pintype "passive")
		)
		(pad "2" smd roundrect
			(at 0.48 0 180)
			(size 0.59 0.64)
			(layers "F.Cu" "F.Paste" "F.Mask")
			(roundrect_rratio 0.25)
			(net 10 "+3V3")
			(pintype "passive")
		)
	)
	(footprint "antmicro-footprints:TP_SMD_1.5mm"
		(layer "F.Cu")
		(at 145 118)
		(property "Reference" "TP4"
			(at -0.4 -1 0)
			(layer "F.SilkS")
			(hide yes)
			(effects
				(font
					(size 0.7 0.7)
					(thickness 0.15)
				)
				(justify left bottom)
			)
		)
		(property "Value" "TP_1.5mm_SMD"
			(at 0 1.7 0)
			(layer "F.Fab")
			(effects
				(font
					(size 0.7 0.7)
					(thickness 0.15)
				)
				(justify left bottom)
			)
		)
		(property "Footprint" "antmicro-footprints:TP_SMD_1.5mm"
			(at 0 0 0)
			(layer "F.Fab")
			(hide yes)
			(effects
				(font
					(size 1.27 1.27)
					(thickness 0.15)
				)
			)
		)
		(property "Author" "Antmicro"
			(at 0 0 0)
			(layer "F.Fab")
			(hide yes)
			(effects
				(font
					(size 1 1)
					(thickness 0.15)
				)
			)
		)
		(property "License" "Apache-2.0"
			(at 0 0 0)
			(layer "F.Fab")
			(hide yes)
			(effects
				(font
					(size 1 1)
					(thickness 0.15)
				)
			)
		)
		(property "MPN" ""
			(at 0 0 0)
			(layer "F.Fab")
			(hide yes)
			(effects
				(font
					(size 1 1)
					(thickness 0.15)
				)
			)
		)
		(property "Manufacturer" ""
			(at 0 0 0)
			(layer "F.Fab")
			(hide yes)
			(effects
				(font
					(size 1 1)
					(thickness 0.15)
				)
			)
		)
		(sheetname "Supply")
		(sheetfile "supply.kicad_sch")
		(attr exclude_from_pos_files exclude_from_bom)
		(fp_circle
			(center 0 0)
			(end 0.85 0)
			(stroke
				(width 0.05)
				(type default)
			)
			(fill none)
			(layer "F.CrtYd")
		)
		(fp_text user "${REFERENCE}"
			(at -0.7 2.9 0)
			(layer "F.Fab")
			(hide yes)
			(effects
				(font
					(size 0.7 0.7)
					(thickness 0.15)
				)
				(justify left bottom)
			)
		)
		(fp_text user "License: Apache-2.0"
			(at -0.7 5.301 0)
			(layer "F.Fab")
			(hide yes)
			(effects
				(font
					(size 0.7 0.7)
					(thickness 0.15)
				)
				(justify left bottom)
			)
		)
		(fp_text user "Author: Antmicro"
			(at -0.7 4.101 0)
			(layer "F.Fab")
			(hide yes)
			(effects
				(font
					(size 0.7 0.7)
					(thickness 0.15)
				)
				(justify left bottom)
			)
		)
		(pad "1" smd circle
			(at 0 0 270)
			(size 1.5 1.5)
			(layers "F.Cu" "F.Mask")
			(net 10 "+3V3")
			(pinfunction "1")
			(pintype "passive")
		)
	)
)
